M48
INCH,TZ
T01C.01
T02C.012
T03C.028
T04C.071
T05C.139
T06C.086
T07C.093
;LEADER: 12 
;HEADER: 
;CODE  : ASCII 
;FILE  : 15968-1a-1-6.drl for board 15968-1a.brd ... layers TOP and BOTTOM
;T01 Holesize 1. = 10.000000 Tolerance = +0.000000/-0.000000 PLATED MILS Quantity = 509
;T02 Holesize 2. = 12.000000 Tolerance = +0.000000/-0.000000 PLATED MILS Quantity = 164
;T03 Holesize 3. = 28.000000 Tolerance = +0.000000/-0.000000 PLATED MILS Quantity = 328
;T04 Holesize 4. = 71.000000 Tolerance = +0.000000/-0.000000 PLATED MILS Quantity = 4
;T05 Holesize 5. = 139.000000 Tolerance = +0.000000/-0.000000 PLATED MILS Quantity = 2
;T06 Holesize 6. = 86.000000 Tolerance = +0.000000/-0.000000 NON_PLATED MILS Quantity = 6
;T07 Holesize 7. = 93.000000 Tolerance = +0.000000/-0.000000 NON_PLATED MILS Quantity = 4
%
G90
T01
X6487Y165762
X14947Y165971
X6487Y175762
X14947Y175971
X6487Y185762
X14947Y185971
X26300Y190800
X22700
X6487Y195762
X14947Y195971
X23000Y201000
X26600
X6487Y205762
Y215762
Y225762
Y235762
X25453Y235870
X15453
X55453
X45453
X35453
X59600Y214000
X56500Y202900
X56300Y180000
X56400Y164250
X59400Y151000
X45200Y89400
X48800Y87100
X39900Y72800
X30700Y56400
X45800Y54800
X83200Y60000
X88000Y65200
X87900Y94500
X87250Y100650
X81800Y125900
X85900Y126300
X81700Y129700
X85700Y129900
X79200Y138100
X68800Y139000
X77000Y140300
X81300Y140400
X79000Y142500
X62000Y142900
X69000Y143300
X62700Y150100
X66100Y151000
X80000Y158900
X67750Y160700
X80400Y167200
X71500Y168500
X83500Y189000
X72200Y202400
X79843Y202676
X75591
X67500Y213500
X64000
X89600Y232900
X84400
X65453Y235870
X75453
X98400Y233100
X94900Y233000
X100500Y209300
X96000Y192000
X100800Y189700
X100700Y186300
Y182900
X100000Y175700
X104743Y174953
X98900Y172350
X116100Y169700
X109500Y168752
Y164500
X92400Y163100
X111924Y156724
X116176
X105400Y153600
X106500Y149000
X101500Y139900
X105218Y137218
X101500Y135908
X102202Y131798
X98900Y126800
X117600Y117700
X111800Y113700
X105500Y109500
X111750Y98450
X114850Y95650
X93900Y95300
X104600Y95000
X106800Y92700
X102400Y92600
X104600Y90500
X110781Y87200
X98300Y72000
Y67500
X117200Y65750
X116900Y59450
X104500Y56200
X99200Y18100
X99000Y13800
X111018Y11382
X107400Y11300
X98200Y10000
X94042Y9842
X92940Y6625
X116900Y-35400
X135182Y-53409
X144631
X126800
X146600Y3400
X147878Y13326
X148300Y16700
X121801Y16999
X132600Y39900
X137900Y49400
X137400Y61900
X129400Y62200
X134000Y63400
X147900Y73800
X124100Y78900
X124900Y88900
X125000Y93400
X124400Y103100
X148950Y109600
X121700Y117300
X120400Y169800
X125300Y170200
X164200Y205100
X173300Y204969
X172300Y192800
X179900Y191300
X175600Y166800
X172000
X152650Y109800
X156600
X159450Y97400
X151550Y87500
X151150Y83500
X161800Y71100
X161400Y58700
X154300Y56400
X161694Y55106
X154300Y49600
X152900Y46500
X176300Y45200
X169800Y39200
X174400Y32500
X153300Y22300
X161100Y13600
X159450Y8750
X160400Y4900
X163529Y-53409
X172977
X154080
X201324
X191875
X195200Y5700
X198900Y21200
X200500Y31500
X202800Y50200
X193900Y51600
X182000Y66700
X181700Y72700
X198300Y73200
X199400Y81400
X196400Y91600
X198300Y111700
X181400Y124500
X199900Y161600
X195900Y162100
X202300Y165100
X192200Y166700
X188900Y173300
X196850Y177950
X180076Y179876
X180000Y183500
X191600Y185600
X180300Y187200
X180000Y198500
X183683Y198517
X209400Y200100
X224100
X239400Y191500
X230500Y191400
X225600Y185900
X225100Y168100
X236900Y85800
X233800Y66000
X218900Y65600
X233700Y54400
X216300Y46700
X230300Y45100
X226600Y21400
X235600Y5300
X221900Y5100
X239119Y-53409
X210773
X229670
X220221
X267466
X258017
X248568
X247200Y5400
X240100Y20900
X252300Y22200
X255900Y35000
X246500Y47900
X246800Y112500
X262400Y169900
X267500Y182000
X266000Y185100
X243000Y185300
X254900Y188300
X250100Y193000
X256747Y199700
X242800Y200600
X294600Y201300
X295800Y195900
X289600Y162100
X274400Y161700
X295812Y-53409
X276914
X286363
X305261
X324158
X314710
X320021Y-46464
X324021
X329742Y-41479
X319070Y-41541
X324642Y-41479
X329242Y-36479
X325242
X328000Y30500
X324600Y36900
X329400Y50300
X328000Y59000
X300800Y100100
X313400Y119100
X328655Y170950
X308600Y171100
X327200Y174024
Y178276
X326600Y182000
X323243Y183323
X321600Y186300
X301500
X329400Y195900
X334794Y195294
X332000Y192200
X348200Y169900
X356700Y86600
X346150Y84800
X355300Y81400
X339100Y73300
X349701Y64199
X353100Y63900
X349700Y56000
X353098Y55882
X352138Y50729
X355536Y50589
X355399Y47191
X359023Y47177
X337900Y46800
X339649Y41539
X352700Y40000
X358700Y38100
X355370Y37411
X343524Y36971
X351500Y36100
X346000Y34640
X355300Y33900
X350300Y31800
X349000Y28300
X352600Y7600
X345642Y-36479
X339442
X359842
X355842
X335442
X349642
X334842Y-41479
X355242
X350142
X345042
X339942
X354621Y-46464
X350621
X330221
X344421
X340421
X334221
X343056Y-53409
X333607
X352505
X370400Y88200
X377800Y87800
X375514Y85000
X372114
X383500Y69200
X361600Y69100
X383500Y65800
X383600Y59618
Y55532
X383300Y50700
X383400Y46600
X388000Y41600
X384000
X372400Y41100
X362100Y38100
X388006Y37706
X373300Y35400
X362400Y34500
X380200Y25800
X380300Y21600
X380500Y17100
Y13200
X380200Y6800
Y3300
X366042Y-36479
X376242
X386442
X370042
X380242
X375642Y-41479
X365442
X385842
X360342
X380742
X370542
X385221Y-46464
X364821
X360821
X375021
X371021
X381221
X371403Y-53409
X361954
X380851
X390300
X399815Y-52741
X391421Y-46464
X395421
X396042Y-41479
X390942
X401142
X410052Y-36825
X400642Y-36479
X390442
X396642
X415100Y3400
X405800Y21100
X418650Y22850
X408600Y23124
Y27376
X405500Y29200
X391600Y29400
X412000Y29900
X394500Y34000
X418705Y34695
X391200Y35700
X404500Y36300
X416300Y37100
X401211Y46589
X404500Y47769
X409026Y61211
X395406Y66092
X398805Y66200
X409400Y69800
X405569Y72731
X405600Y87500
X402500Y89124
Y93376
X405800Y94200
X448200Y93000
X437300Y91100
X439000Y87700
X448369Y86631
X441688Y74914
X425971Y62050
X426113Y59046
X432091Y56151
X426065Y56213
X429056Y56135
X420322Y56072
X423202Y56119
X426128Y53348
Y50188
X423500Y37800
X431382Y35283
X423500Y34200
X449400Y26433
X439418Y26110
X435287Y25646
X429850Y22950
X428600Y16900
X438900Y13400
X433900Y11000
X423852Y4375
X436752Y4175
X432452Y-36225
X420252Y-36925
X445252Y-37225
X447252Y-47725
X446252Y-53425
X465149
X474598
X455701
X454500Y29300
X459652Y31575
X454000Y40600
X457400Y41800
X458100Y47300
X461513Y48758
Y52267
X458100Y53700
X468588Y55981
X454085Y63272
X452496Y70099
X469300Y87600
X451381Y88210
Y91719
X453736Y105151
X457245
X452888Y108444
X457097Y108548
X455700Y205800
X466010Y216328
X467506Y226106
X466361Y230936
X479761Y236336
X505961Y236936
X488161Y236336
X499761
X502000Y229400
X480761Y227936
X492961Y227336
X498052Y-625
X490200Y-6400
X488652Y-18225
X496352Y-19025
X493496Y-53425
X484047
X502945
X531291
X521842
X512393
X530994Y-38000
X524994
X523300Y-32100
X531600Y-31800
X532691Y-17725
X528590Y-12237
Y2763
X532137Y7890
X532778Y21738
X534737Y40290
X534337Y52790
X534637Y74290
Y92590
X517900Y103300
X511900Y142700
X520500Y154500
X525000Y158000
X521600Y158400
X512000
X529000Y158500
X511900Y174400
X521900Y179500
X524200Y181600
X519700Y181900
X521900Y184000
X520970Y192569
X528500Y200000
X524000
X519761Y236336
X529500Y236400
X537200
X545300Y236800
X559761Y236336
X548300Y178100
X551376Y176271
Y172019
X548200Y169900
X593337Y166890
X578337
X593337Y176890
X577748Y181113
X593337Y186890
X577748Y191113
X593337Y196890
X577748Y201113
X593337Y206890
X577748Y211113
X593337Y216890
X578337Y226890
X593337
X579761Y236336
X599761
X608337Y226890
Y216890
Y206890
Y196890
Y186890
Y176890
Y166890
T02
X49400Y60000
X21600Y74000
X21800Y78600
X24400Y81900
X22300Y85000
X27207Y85293
X30600Y88100
X25700Y89200
X33700Y91400
X29400Y92300
X32800Y95000
X33200Y98700
X31000Y156900
X28200Y160400
X32400Y160600
X36000Y161800
X29200Y164000
X33100Y164800
X39200Y212100
X44200Y212200
X44400Y217400
X39300
X59700Y115200
X54600Y114900
X54400Y110000
X59000Y107900
X78000Y105800
X55600Y105100
X64600Y104500
X78000Y99900
X64200Y99200
X78900Y82400
X50700Y81900
X54300Y81700
X58000Y81600
X96000Y80100
X76300Y79700
X93800Y77000
X97800Y76800
X89800Y76700
X73500Y76600
X78200Y76200
X67400
X71000Y73500
X93000Y73300
X74700Y73100
X78300Y72600
X67200Y72400
X71100Y69800
X74800Y69500
X78400Y68900
X67200Y68800
X74900Y65800
X53000Y59800
X75500Y55400
X79099Y55280
X83400Y55300
X87300
X71500Y39500
X69300Y36500
X78600Y36200
X82300
X74600Y36100
X86000Y36087
X71700Y31500
X69400Y26700
X90100Y23100
X72400Y22300
X84619Y-27663
X90332Y-30191
X79035Y-30696
X85231Y-34026
X79103Y-35748
X90400Y-36500
X85442Y-39927
X79444Y-41282
X90546Y-41425
X84671Y-44973
X79444Y-46817
X89467Y-47981
X95906Y-53300
X111100Y-53100
X106800Y-53000
X111300Y-49100
X107000Y-49000
X111400Y-37000
X107100Y-36900
X111800Y-33300
X107500Y-33200
X119300Y3800
X123000
X127000Y3900
X130800Y4000
X115500
X111600Y4100
X107800Y4300
X110800Y28100
X107000Y28300
X103000
X109600Y40000
X105800Y40200
X102000Y40300
X139122Y78644
X131666Y78581
X135425Y78592
X135025Y85092
X131266Y85081
X138722Y85144
X131466Y94781
X138922Y94844
X135225Y94792
X140552Y117907
X136626Y118116
X146165Y120044
X135100Y161900
X134900Y165700
X145300Y201100
X148314Y203751
X142500Y203900
X165700Y195000
X162100Y193800
X167100Y181200
X163300Y178900
X155600Y166300
X151700
X158000Y124800
Y120900
X158100Y116300
X172300Y94300
X169800Y91100
X174900Y90900
X153000Y40700
X152279Y36876
X152700Y33300
X363700Y78200
X428500Y107700
X432100Y103800
X424200
X421405Y90902
X423690Y87875
X418437Y87727
X449900Y-5700
Y-9700
X449800Y-13500
X453400
X453500Y-9800
Y-5700
X453600Y-2000
X450000Y-1900
X456662Y76376
X460535Y76560
X495500Y210500
X495400Y215300
X495500Y219600
X504800
X519900Y219500
X527000
X540500
X500200
X532200Y219300
X504700Y215300
X500100Y215200
X504500Y210600
X500200Y210400
T03
X122403Y138269
X126338Y130394
X130278Y138269
X134213Y130394
X138148Y138269
X142088Y130394
X146023Y138269
X149963Y130394
X153898Y138269
X157833Y130394
X161773Y138269
X173583Y130394
X177518Y138269
X181458Y130394
X185393Y138269
X189333Y130394
X193268Y138269
X197203Y130394
X201143Y138269
X205078Y130394
X209018Y138269
X212953Y130394
X216888Y138269
X220828Y130394
X224763Y138269
X228703Y130394
X232638Y138269
X236573Y130394
X240513Y138269
X244448Y130394
X248388Y138269
X252323Y130394
X256258Y138269
X260198Y130394
X264133Y138269
X268073Y130394
X272008Y138269
X275943Y130394
X279883Y138269
X283818Y130394
X287758Y138269
X291693Y130394
X295628Y138269
X299568Y130394
X303503Y138269
X307443Y130394
X311378Y138269
X315313Y130394
X319253Y138269
X323188Y130394
X327128Y138269
X331063Y130394
X334998Y138269
X338938Y130394
X342873Y138269
X346813Y130394
X350748Y138269
X354683Y130394
X358623Y138269
X362558Y130394
X366498Y138269
X370433Y130394
X374368Y138269
X378308Y130394
X382243Y138269
X386183Y130394
X390118Y138269
X394053Y130394
X397993Y138269
X401928Y130394
X405868Y138269
X409803Y130394
X413738Y138269
X417678Y130394
X421613Y138269
X425553Y130394
X429488Y138269
X433423Y130394
X437363Y138269
X441298Y130394
X445238Y138269
X449173Y130394
X445238Y148109
X437363
X429488
X421613
X413738
X405868
X397993
X390118
X382243
X374368
X366498
X358623
X350748
X342873
X334998
X327128
X319253
X311378
X303503
X295628
X287758
X279883
X272008
X264133
X256258
X248388
X240513
X232638
X224763
X216888
X209018
X201143
X193268
X185393
X177518
X161773
X153898
X146023
X138148
X130278
X122403
X126338Y155984
X134213
X142088
X149963
X157833
X173583
X181458
X189333
X197203
X205078
X212953
X220828
X228703
X236573
X244448
X252323
X260198
X268073
X275943
X283818
X291693
X299568
X307443
X315313
X323188
X331063
X338938
X346813
X354683
X362558
X370433
X378308
X386183
X394053
X401928
X409803
X417678
X425553
X433423
X441298
X449173
Y210394
X445238Y218269
X441298Y210394
X437363Y218269
X433423Y210394
X429488Y218269
X425553Y210394
X421613Y218269
X417678Y210394
X413738Y218269
X409803Y210394
X405868Y218269
X401928Y210394
X397993Y218269
X394053Y210394
X390118Y218269
X386183Y210394
X382243Y218269
X378308Y210394
X374368Y218269
X370433Y210394
X366498Y218269
X362558Y210394
X358623Y218269
X354683Y210394
X350748Y218269
X346813Y210394
X342873Y218269
X338938Y210394
X334998Y218269
X331063Y210394
X327128Y218269
X323188Y210394
X319253Y218269
X315313Y210394
X311378Y218269
X307443Y210394
X303503Y218269
X299568Y210394
X295628Y218269
X291693Y210394
X287758Y218269
X283818Y210394
X279883Y218269
X275943Y210394
X272008Y218269
X268073Y210394
X264133Y218269
X260198Y210394
X256258Y218269
X252323Y210394
X248388Y218269
X244448Y210394
X240513Y218269
X236573Y210394
X232638Y218269
X228703Y210394
X224763Y218269
X220828Y210394
X216888Y218269
X212953Y210394
X209018Y218269
X205078Y210394
X201143Y218269
X197203Y210394
X193268Y218269
X189333Y210394
X185393Y218269
X181458Y210394
X177518Y218269
X173583Y210394
X161773Y218269
X157833Y210394
X153898Y218269
X149963Y210394
X146023Y218269
X142088Y210394
X138148Y218269
X134213Y210394
X130278Y218269
X126338Y210394
X122403Y218269
Y228109
X130278
X138148
X146023
X153898
X161773
X177518
X185393
X193268
X201143
X209018
X216888
X224763
X232638
X240513
X248388
X256258
X264133
X272008
X279883
X287758
X295628
X303503
X311378
X319253
X327128
X334998
X342873
X350748
X358623
X366498
X374368
X382243
X390118
X397993
X405868
X413738
X421613
X429488
X437363
X445238
X449173Y235984
X441298
X433423
X425553
X417678
X409803
X401928
X394053
X386183
X378308
X370433
X362558
X354683
X346813
X338938
X331063
X323188
X315313
X307443
X299568
X291693
X283818
X275943
X268073
X260198
X252323
X244448
X236573
X228703
X220828
X212953
X205078
X197203
X189333
X181458
X173583
X157833
X149963
X142088
X134213
X126338
T04
X539370Y190256
Y206792
X561024
Y190256
T05
X15748Y128150
X542913
T06
X21800Y-41500
X14794Y226306
X542107Y17432
X610300Y-43600
X585785Y228866
X612500Y540800
T07
X168268Y143189
Y223189
X456258
Y143189
M30
